FILE_TYPE = CONNECTIVITY;
{Allegro Design Entry HDL 16.6-p007 (v16-6-112F) 10/10/2012}
"PAGE_NUMBER" = 240;
0"NC";
1"GND\g";
2"P5V_STBY\g";
3"GND\g";
4"GND\g";
5"P3V3_STBY\g";
6"P12V_STBY\g";
7"GND\g";
8"GND\g";
9"GND\g";
10"GND\g";
11"GND\g";
12"GND\g";
13"GND\g";
14"GND\g";
15"AGND_P3V3_STBY\g";
16"AGND_P3V3_STBY\g";
17"AGND_P3V3_STBY\g";
18"AGND_P3V3_STBY\g";
19"AGND_P3V3_STBY\g";
20"AGND_P3V3_STBY\g";
21"GND\g";
22"P3V3_STBY\g";
23"GND\g";
24"GND\g";
25"GND\g";
26"GND\g";
27"P3V3_STBY\g";
28"PWRGD_P3V3_STBY_R";
29"VR_P3V3_STBY_BOOT_R";
30"VSENSE_RGND_P3V3_STBY";
31"PWRGD_P5V_STBY";
32"VSENSE_VOUT_P3V3_STBY";
33"VR_P3V3_STBY_BOOT";
34"PWRGD_P3V3_STBY";
35"VR_P3V3_STBY_EN";
36"VSENSE_P3V3_STBY";
37"VR_P3V3_STBY_UGATE";
38"VR_P3V3_STBY_LGATE";
39"VR_P3V3_STBY_SNUB";
40"VR_P3V3_STBY_OCSELECT";
41"VR_P3V3_STBY_PHASE";
42"VR_FET_SW_P12V_STBY_P3V3_STBY";
43"GND\g";
%"GND"
"1","(5625,2150)","0","mstr_symbols","I110";
;
ROOM"PVPP_KLM_VR"
BOM_COST"PVPP_KLM_VR"
BOM"SYSB_CPLD"
CDS_LIB"mstr_symbols"
VOLTAGE"0"
SIZE"1B"
BODY_TYPE"PLUMBING"
HDL_POWER"GND";
"A\NAC"1;
%"RES"
"2","(5625,2400)","0","mstr_discrete","I111";
;
WATTAGE"1/16W"
MATERIAL"EMPTY"
PACK_TYPE"0402"
TOLERANCE"1%"
VALUE"10.0K"
LOCATION"R8F1"
PART_NUMBER"G21796-016"
CDS_LIB"mstr_discrete"
CDS_LOCATION"R8F1"
ROOM"P3V3_STBY_VR"
$SEC"1"
CDS_SEC"1"
BOM"SYSB_CPLD"
BOM_COST"P3V3_STBY_VR";
"A"
$PN"1"31;
"B"
$PN"2"1;
%"CAP"
"1","(6175,2475)","2","mstr_discrete","I113";
;
VALUE"1000PF"
TOLERANCE"10%"
PACK_TYPE"0402LF"
MATERIAL"EMPTY"
VOLTAGE"50V"
LOCATION"C8E17"
PART_NUMBER"A36096-046"
CDS_LOCATION"C8E17"
$SEC"1"
CDS_SEC"1"
REUSE_ID"1"
FIN"VR_1P2"
ROOM"P3V3_STBY_VR"
CDS_LIB"mstr_discrete"
BOM_COST"P3V3_STBY_VR";
"A"
$PN"1"31;
"B"
$PN"2"17;
%"P5V_STBY"
"1","(5725,3600)","0","mstr_symbols","I114";
;
VOLTAGE"+5.0V"
CDS_LIB"mstr_symbols"
SIZE"1B"
BODY_TYPE"PLUMBING"
HDL_POWER"P5V_STBY";
"G\NAC"2;
%"GND"
"1","(6350,3100)","0","mstr_symbols","I115";
;
BOM_COST"PVPP_KLM_VR"
ROOM"PVPP_KLM_VR"
CDS_LIB"mstr_symbols"
VOLTAGE"0"
SIZE"1B"
BODY_TYPE"PLUMBING"
HDL_POWER"GND";
"A\NAC"3;
%"CAP"
"1","(6350,3350)","0","mstr_discrete","I116";
;
VOLTAGE"50V"
TOLERANCE"10%"
PACK_TYPE"0402LF"
PART_NUMBER"A36096-046"
LOCATION"C8F2"
VALUE"1000PF"
MATERIAL"X7R"
BOM_COST"P3V3_STBY_VR"
CDS_LIB"mstr_discrete"
ROOM"P3V3_STBY_VR"
$SEC"1"
CDS_LOCATION"C8F2"
CDS_SEC"1"
REUSE_ID"17";
"A"
$PN"1"28;
"B"
$PN"2"3;
%"RES"
"2","(6275,3900)","2","mstr_discrete","I117";
;
CDS_SEC"1"
LOCATION"R8F5"
VALUE"1.00K"
TOLERANCE"1%"
WATTAGE"1/16W"
MATERIAL"CHIP"
PART_NUMBER"G21796-026"
PACK_TYPE"0402"
CDS_LOCATION"R8F5"
CDS_LIB"mstr_discrete"
ROOM"PVPP_KLM_VR"
BOM_COST"P3V3_STBY_VR"
SEC"1"
REUSE_ID"21"
SEC_TYPE"0402";
"A"
$PN"1"5;
"B"
$PN"2"28;
%"RT8240"
"1","(7550,2625)","0","mstr_vreg","I125";
;
CDS_SEC"1"
LOCATION"EU8F1"
MATERIAL"IC"
PART_NUMBER"H66262-001"
CDS_LIB"mstr_vreg"
ROOM"P3V3_STBY_VR"
CDS_LOCATION"EU8F1"
SEC"1"
SEC_TYPE"QFN"
PACK_TYPE"QFN";
"GND<0>"
$PN"12"15;
"CS"
$PN"10"40;
"GND<1>"
$PN"13"15;
"RGND"
$PN"7"30;
"VOUT"
$PN"6"32;
"LGATE"
$PN"1"38;
"PHASE"
$PN"2"41;
"UGATE"
$PN"3"37;
"BOOT"
$PN"4"33;
"G0"
$PN"11"15;
"EN"
$PN"8"35;
"PGOOD"
$PN"9"28;
"VCC"
$PN"5"2;
%"RES"
"1","(7600,3425)","0","mstr_discrete","I127";
;
VALUE"0.0"
WATTAGE"1/16W"
TOLERANCE"5%"
LOCATION"R8E35"
PACK_TYPE"0402"
PART_NUMBER"G21497-005"
MATERIAL"CHIP"
CDS_LOCATION"R8E35"
ROOM"P3V3_STBY_VR"
CDS_LIB"mstr_discrete"
BOM_COST"P3V3_STBY_VR"
SPOF"TRUE"
REUSE_ID"13"
CDS_SEC"1"
$SEC"1";
"B"
$PN"2"29;
"A"
$PN"1"33;
%"GND"
"1","(8475,4150)","0","mstr_symbols","I128";
;
VOLTAGE"0"
CDS_LIB"mstr_symbols"
BOM_COST"PVPP_KLM_VR"
ROOM"PVPP_KLM_VR"
SIZE"1B"
BODY_TYPE"PLUMBING"
HDL_POWER"GND";
"A\NAC"4;
%"CAP"
"2","(8300,3425)","2","mstr_discrete","I129";
;
MATERIAL"X7R"
PACK_TYPE"0603LF"
VOLTAGE"25V"
VALUE"0.1UF"
LOCATION"C8E12"
TOLERANCE"10%"
PART_NUMBER"602433-020"
ROOM"P3V3_STBY_VR"
CDS_LOCATION"C8E12"
CDS_LIB"mstr_discrete"
BOM_COST"P3V3_STBY_VR"
REUSE_ID"27"
SPOF"TRUE"
CDS_SEC"1"
$SEC"1";
"A"
$PN"1"41;
"B"
$PN"2"29;
%"P3V3_STBY"
"1","(6275,4150)","0","mstr_symbols","I130";
;
CDS_LIB"mstr_symbols"
SIZE"1B"
VOLTAGE"+3.3V"
BODY_TYPE"PLUMBING"
HDL_POWER"P3V3_STBY";
"G\NAC"5;
%"P12V_STBY"
"1","(5700,4750)","0","mstr_symbols","I131";
;
SIZE"1B"
CDS_LIB"mstr_symbols"
VOLTAGE"12.0V"
BODY_TYPE"PLUMBING"
HDL_POWER"P12V_STBY";
"G\NAC"6;
%"CAP"
"1","(8150,4325)","0","mstr_discrete","I137";
;
PART_NUMBER"D38464-005"
PACK_TYPE"1206LF"
TOLERANCE"10%"
VOLTAGE"16V"
VALUE"22UF"
LOCATION"C8E10"
MATERIAL"X6S"
CDS_SEC"1"
$SEC"1"
CDS_LOCATION"C8E10"
BOM_COST"P3V3_STBY_VR"
CDS_LIB"mstr_discrete"
ROOM"P3V3_STBY_VR";
"A"
$PN"1"42;
"B"
$PN"2"43;
%"GND"
"1","(8150,4175)","0","mstr_symbols","I138";
;
SIZE"1B"
VOLTAGE"0"
CDS_LIB"mstr_symbols"
ROOM"PVPP_KLM_VR"
BOM_COST"PVPP_KLM_VR"
BODY_TYPE"PLUMBING"
HDL_POWER"GND";
"A\NAC"43;
%"CAP"
"1","(8475,4350)","0","mstr_discrete","I139";
;
LOCATION"C8E14"
TOLERANCE"10%"
VOLTAGE"16V"
PART_NUMBER"D97712-011"
MATERIAL"X6S"
VALUE"1.0UF"
PACK_TYPE"0402"
REUSE_ID"1"
FIN"VR_1P2"
CDS_SEC"1"
$SEC"1"
CDS_LOCATION"C8E14"
ROOM"P3V3_STBY_VR"
BOM_COST"P3V3_STBY_VR"
CDS_LIB"mstr_discrete";
"A"
$PN"1"42;
"B"
$PN"2"4;
%"RES"
"1","(9225,925)","0","mstr_discrete","I140";
;
VALUE"0.0"
MATERIAL"CHIP"
TOLERANCE"5%"
WATTAGE"1/16W"
PART_NUMBER"G21497-005"
LOCATION"R8E38"
PACK_TYPE"0402"
CDS_LOCATION"R8E38"
CDS_SEC"1"
$SEC"1"
ROOM"P3V3_STBY_VR"
CDS_LIB"mstr_discrete"
BOM_COST"P3V3_STBY_VR";
"B"
$PN"2"19;
"A"
$PN"1"30;
%"RES"
"2","(9475,1100)","0","mstr_discrete","I142";
;
PART_NUMBER"G21796-016"
PACK_TYPE"0402"
LOCATION"R8E34"
MATERIAL"CHIP"
WATTAGE"1/16W"
TOLERANCE"1%"
VALUE"10.0K"
BOM_COST"P3V3_STBY_VR"
ROOM"P3V3_STBY_VR"
CDS_LIB"mstr_discrete"
CDS_LOCATION"R8E34"
$SEC"1"
SPOF"TRUE"
REUSE_ID"7"
CDS_SEC"1";
"A"
$PN"1"32;
"B"
$PN"2"19;
%"RES"
"2","(9475,1425)","0","mstr_discrete","I143";
;
WATTAGE"1/16W"
PACK_TYPE"0402"
PART_NUMBER"G21796-114"
MATERIAL"CHIP"
TOLERANCE"1%"
LOCATION"R8E31"
VALUE"23.2K"
CDS_LIB"mstr_discrete"
ROOM"P3V3_STBY_VR"
CDS_LOCATION"R8E31"
$SEC"1"
CDS_SEC"1"
REUSE_ID"9"
BOM_COST"P3V3_STBY_VR"
SPOF"TRUE";
"A"
$PN"1"36;
"B"
$PN"2"32;
%"RES"
"1","(9525,1800)","5","mstr_discrete","I144";
;
CDS_SEC"1"
PACK_TYPE"0402"
MATERIAL"CHIP"
PART_NUMBER"G21497-005"
WATTAGE"1/16W"
TOLERANCE"5%"
VALUE"0.0"
LOCATION"R8E25"
CDS_LOCATION"R8E25"
SEC"1"
SPOF"TRUE"
SEC_TYPE"0402"
CDS_LIB"mstr_discrete"
ROOM"PVPP_KLM_VR";
"B"
$PN"2"36;
"A"
$PN"1"27;
%"GND"
"1","(10175,1625)","0","mstr_symbols","I145";
;
BOM_COST"PVPP_KLM_VR"
ROOM"PVPP_KLM_VR"
CDS_LIB"mstr_symbols"
VOLTAGE"0"
SIZE"1B"
BODY_TYPE"PLUMBING"
HDL_POWER"GND";
"A\NAC"7;
%"RES"
"1","(10475,1725)","0","mstr_discrete","I146";
;
PART_NUMBER"G21497-005"
VALUE"0.0"
PACK_TYPE"0402"
WATTAGE"1/16W"
MATERIAL"CHIP"
LOCATION"R8F11"
TOLERANCE"5%"
CDS_LIB"mstr_discrete"
CDS_LOCATION"R8F11"
CDS_SEC"1"
$SEC"1"
ROOM"P3V3_STBY_VR";
"B"
$PN"2"20;
"A"
$PN"1"7;
%"GND"
"1","(9650,3150)","0","mstr_symbols","I147";
;
BOM_COST"PVPP_KLM_VR"
SIZE"1B"
ROOM"PVPP_KLM_VR"
VOLTAGE"0"
CDS_LIB"mstr_symbols"
BODY_TYPE"PLUMBING"
HDL_POWER"GND";
"A\NAC"8;
%"RES"
"2","(9750,3550)","0","mstr_discrete","I148";
;
WATTAGE"1/16W"
TOLERANCE"5%"
VALUE"2.2"
PART_NUMBER"G21497-016"
PACK_TYPE"0402"
LOCATION"R8F3"
MATERIAL"EMPTY"
BOM_COST"P3V3_STBY_VR"
REUSE_ID"29"
CDS_SEC"1"
$SEC"1"
ROOM"P3V3_STBY_VR"
CDS_LOCATION"R8F3"
CDS_LIB"mstr_discrete";
"A"
$PN"1"39;
"B"
$PN"2"9;
%"GND"
"1","(9750,3350)","0","mstr_symbols","I149";
;
SIZE"1B"
VOLTAGE"0"
CDS_LIB"mstr_symbols"
ROOM"PVPP_KLM_VR"
BOM_COST"PVPP_KLM_VR"
BODY_TYPE"PLUMBING"
HDL_POWER"GND";
"A\NAC"9;
%"GND"
"1","(10750,3550)","0","mstr_symbols","I151";
;
BOM_COST"PVPP_KLM_VR"
ROOM"PVPP_KLM_VR"
SIZE"1B"
VOLTAGE"0"
CDS_LIB"mstr_symbols"
BODY_TYPE"PLUMBING"
HDL_POWER"GND";
"A\NAC"10;
%"RES"
"2","(10750,3800)","0","mstr_discrete","I152";
;
LOCATION"R2T4"
WATTAGE"1/16W"
TOLERANCE"0.1%"
MATERIAL"CHIP"
VALUE"1.0K"
PACK_TYPE"0402"
PART_NUMBER"G85996-004"
REUSE_ID"34"
CDS_SEC"1"
$SEC"1"
BOM_COST"P3V3_STBY_VR"
CDS_LOCATION"R2T4"
ROOM"P3V3_STBY_VR"
CDS_LIB"mstr_discrete";
"A"
$PN"1"27;
"B"
$PN"2"10;
%"GND"
"1","(11100,3550)","0","mstr_symbols","I153";
;
SIZE"1B"
CDS_LIB"mstr_symbols"
VOLTAGE"0"
ROOM"PVPP_KLM_VR"
BOM_COST"PVPP_KLM_VR"
BODY_TYPE"PLUMBING"
HDL_POWER"GND";
"A\NAC"11;
%"GND"
"1","(11500,3550)","0","mstr_symbols","I156";
;
VOLTAGE"0"
SIZE"1B"
CDS_LIB"mstr_symbols"
ROOM"PVPP_KLM_VR"
BOM_COST"PVPP_KLM_VR"
BODY_TYPE"PLUMBING"
HDL_POWER"GND";
"A\NAC"12;
%"GND"
"1","(11950,3600)","0","mstr_symbols","I157";
;
BOM_COST"PVPP_KLM_VR"
ROOM"PVPP_KLM_VR"
SIZE"1B"
CDS_LIB"mstr_symbols"
VOLTAGE"0"
BODY_TYPE"PLUMBING"
HDL_POWER"GND";
"A\NAC"13;
%"CAP"
"1","(11950,3875)","0","mstr_discrete","I158";
;
PART_NUMBER"C95333-008"
MATERIAL"X6S"
PACK_TYPE"0805"
VOLTAGE"6.3V"
VALUE"22UF"
LOCATION"C2T7"
TOLERANCE"20%"
ROOM"P3V3_STBY_VR"
BOM_COST"P3V3_STBY_VR"
CDS_LIB"mstr_discrete"
CDS_LOCATION"C2T7"
$SEC"1"
CDS_SEC"1"
REUSE_ID"33";
"A"
$PN"1"27;
"B"
$PN"2"13;
%"GND"
"1","(12175,3600)","0","mstr_symbols","I159";
;
BOM_COST"PVPP_KLM_VR"
ROOM"PVPP_KLM_VR"
SIZE"1B"
VOLTAGE"0"
CDS_LIB"mstr_symbols"
BODY_TYPE"PLUMBING"
HDL_POWER"GND";
"A\NAC"14;
%"CAP"
"1","(12175,3875)","0","mstr_discrete","I160";
;
MATERIAL"X6S"
PART_NUMBER"C95333-008"
PACK_TYPE"0805"
VOLTAGE"6.3V"
TOLERANCE"20%"
VALUE"22UF"
LOCATION"C2T6"
CDS_SEC"1"
REUSE_ID"33"
$SEC"1"
CDS_LOCATION"C2T6"
BOM_COST"P3V3_STBY_VR"
CDS_LIB"mstr_discrete"
ROOM"P3V3_STBY_VR";
"A"
$PN"1"27;
"B"
$PN"2"14;
%"CAP"
"1","(9750,3900)","0","mstr_discrete","I163";
;
VOLTAGE"50V"
MATERIAL"EMPTY"
PART_NUMBER"A36096-091"
PACK_TYPE"0402LF"
TOLERANCE"10%"
VALUE"3300PF"
LOCATION"C8F3"
REUSE_ID"26"
CDS_SEC"1"
$SEC"1"
BOM_COST"P3V3_STBY_VR"
CDS_LOCATION"C8F3"
ROOM"P3V3_STBY_VR"
CDS_LIB"mstr_discrete";
"A"
$PN"1"41;
"B"
$PN"2"39;
%"AGND_SCSI"
"1","(6975,2100)","0","mstr_symbols","I164";
;
HDL_POWER"AGND_P3V3_STBY"
VOLTAGE"0V"
CDS_LIB"mstr_symbols"
BODY_TYPE"PLUMBING";
"A"15;
%"AGND_SCSI"
"1","(6450,1550)","0","mstr_symbols","I165";
;
HDL_POWER"AGND_P3V3_STBY"
CDS_LIB"mstr_symbols"
VOLTAGE"0V"
BODY_TYPE"PLUMBING";
"A"16;
%"AGND_SCSI"
"1","(6175,2175)","0","mstr_symbols","I166";
;
HDL_POWER"AGND_P3V3_STBY"
VOLTAGE"0V"
CDS_LIB"mstr_symbols"
BODY_TYPE"PLUMBING";
"A"17;
%"AGND_SCSI"
"1","(5500,3100)","0","mstr_symbols","I167";
;
HDL_POWER"AGND_P3V3_STBY"
CDS_LIB"mstr_symbols"
VOLTAGE"0V"
BODY_TYPE"PLUMBING";
"A"18;
%"AGND_SCSI"
"1","(9475,800)","0","mstr_symbols","I168";
;
HDL_POWER"AGND_P3V3_STBY"
VOLTAGE"0V"
CDS_LIB"mstr_symbols"
BODY_TYPE"PLUMBING";
"A"19;
%"AGND_SCSI"
"1","(10725,1625)","0","mstr_symbols","I169";
;
HDL_POWER"AGND_P3V3_STBY"
VOLTAGE"0V"
CDS_LIB"mstr_symbols"
BODY_TYPE"PLUMBING";
"A"20;
%"CSD87384M"
"1","(9250,3400)","0","mstr_discrete","I170";
;
CDS_SEC"1"
PART_NUMBER"H66258-001"
LOCATION"EU8E1"
MATERIAL"IC"
ROOM"P3V3_STBY_VR"
CDS_LOCATION"EU8E1"
SEC"1"
SEC_TYPE"SM"
PACK_TYPE"SM"
CDS_LIB"mstr_discrete";
"BG"
$PN"4"38;
"TG"
$PN"1"37;
"VIN"
$PN"2"42;
"VSW"
$PN"5"41;
"PGND"
$PN"3"8;
%"RES"
"1","(7175,3825)","0","mstr_discrete","I171";
;
CDS_SEC"1"
WATTAGE"1/16W"
VALUE"22.1"
PART_NUMBER"G21796-250"
LOCATION"R8F10"
MATERIAL"CHIP"
PACK_TYPE"0402"
TOLERANCE"1.0%"
ROOM"P3V3_STBY_VR"
CDS_LOCATION"R8F10"
SEC"1"
SEC_TYPE"0402"
CDS_LIB"mstr_discrete";
"B"
$PN"2"34;
"A"
$PN"1"28;
%"CAP"
"1","(12425,3875)","0","mstr_discrete","I174";
;
CDS_SEC"1"
MATERIAL"X6S"
TOLERANCE"20%"
VALUE"22UF"
PART_NUMBER"C95333-008"
VOLTAGE"6.3V"
PACK_TYPE"0805"
LOCATION"C2T9"
SEC_TYPE"0805"
SEC"1"
REUSE_ID"33"
CDS_LOCATION"C2T9"
BOM_COST"P3V3_STBY_VR"
CDS_LIB"mstr_discrete"
ROOM"P3V3_STBY_VR";
"A"
$PN"1"27;
"B"
$PN"2"21;
%"GND"
"1","(12425,3575)","0","mstr_symbols","I175";
;
BOM_COST"PVPP_KLM_VR"
ROOM"PVPP_KLM_VR"
SIZE"1B"
CDS_LIB"mstr_symbols"
VOLTAGE"0"
BODY_TYPE"PLUMBING"
HDL_POWER"GND";
"A\NAC"21;
%"RES"
"1","(6400,2725)","0","mstr_discrete","I176";
;
CDS_SEC"1"
TOLERANCE"5%"
WATTAGE"1/16W"
LOCATION"R8F2"
MATERIAL"CHIP"
VALUE"0.0"
PACK_TYPE"0402"
PART_NUMBER"G21497-005"
ROOM"PVCCIN_CPU0_VR"
CDS_LIB"mstr_discrete"
CDS_LOCATION"R8F2"
SEC_TYPE"0402"
SEC"1";
"B"
$PN"2"35;
"A"
$PN"1"31;
%"RES"
"2","(6950,3250)","0","mstr_discrete","I177";
;
CDS_SEC"1"
LOCATION"R8E40"
PART_NUMBER"G21796-010"
MATERIAL"EMPTY"
WATTAGE"1/16W"
VALUE"100.0K"
TOLERANCE"1%"
PACK_TYPE"0402"
CDS_LIB"mstr_discrete"
CDS_LOCATION"R8E40"
ROOM"BMC"
BOM_COST"SM_CONTROLLER"
SEC"1"
SEC_TYPE"0402";
"A"
$PN"1"22;
"B"
$PN"2"35;
%"P3V3_STBY"
"1","(6950,3500)","0","mstr_symbols","I178";
;
CDS_LIB"mstr_symbols"
SIZE"1B"
VOLTAGE"+3.3V"
BODY_TYPE"PLUMBING"
HDL_POWER"P3V3_STBY";
"G\NAC"22;
%"GND"
"1","(6700,4025)","0","mstr_symbols","I179";
;
CDS_LIB"mstr_symbols"
BOM_COST"PVPP_KLM_VR"
ROOM"PVPP_KLM_VR"
VOLTAGE"0"
SIZE"1B"
BODY_TYPE"PLUMBING"
HDL_POWER"GND";
"A\NAC"23;
%"GND"
"1","(7450,4025)","0","mstr_symbols","I180";
;
SIZE"1B"
VOLTAGE"0"
ROOM"PVPP_KLM_VR"
BOM_COST"PVPP_KLM_VR"
CDS_LIB"mstr_symbols"
BODY_TYPE"PLUMBING"
HDL_POWER"GND";
"A\NAC"24;
%"SC22U16V5MX-4-GP"
"1","(6700,4275)","0","w_hdl","I181";
;
CDS_SEC"1"
CDS_LOCATION"C9F1"
LOCATION"C9F1"
VALUE"SC22U16V5MX-4-GP"
TOLERANCE"20%"
ATTRIBUTE"22UF"
TYPE"X6S"
PACK_SIZE"0805"
RATED"16V"
PACK_TYPE"SMD-BCG5"
SEC"1"
SEC_TYPE"SMD-BCG5"
PART_NUMBER"078.22611.0811"
CDS_LIB"w_hdl"
CDS_LMAN_SYM_OUTLINE"-50,25,50,-25";
"2"
$PN"2"23;
"1"
$PN"1"42;
%"SC22U16V5MX-4-GP"
"1","(7000,4275)","0","w_hdl","I182";
;
CDS_SEC"1"
CDS_LOCATION"C22W11"
VALUE"SC22U16V5MX-4-GP"
LOCATION"C22W11"
TOLERANCE"20%"
RATED"16V"
PACK_SIZE"0805"
TYPE"X6S"
ATTRIBUTE"22UF"
CDS_LMAN_SYM_OUTLINE"-50,25,50,-25"
CDS_LIB"w_hdl"
PART_NUMBER"078.22611.0811"
SEC_TYPE"SMD-BCG5"
SEC"1"
PACK_TYPE"SMD-BCG5";
"2"
$PN"2"26;
"1"
$PN"1"42;
%"SC22U16V5MX-4-GP"
"1","(7450,4275)","0","w_hdl","I183";
;
CDS_SEC"1"
CDS_LOCATION"C8E11"
VALUE"SC22U16V5MX-4-GP"
RATED"16V"
PACK_SIZE"0805"
TYPE"X6S"
TOLERANCE"20%"
ATTRIBUTE"22UF"
LOCATION"C8E11"
CDS_LMAN_SYM_OUTLINE"-50,25,50,-25"
CDS_LIB"w_hdl"
PART_NUMBER"078.22611.0811"
SEC_TYPE"SMD-BCG5"
SEC"1"
PACK_TYPE"SMD-BCG5";
"2"
$PN"2"24;
"1"
$PN"1"42;
%"GND"
"1","(7800,4025)","0","mstr_symbols","I184";
;
CDS_LIB"mstr_symbols"
BOM_COST"PVPP_KLM_VR"
ROOM"PVPP_KLM_VR"
VOLTAGE"0"
SIZE"1B"
BODY_TYPE"PLUMBING"
HDL_POWER"GND";
"A\NAC"25;
%"GND"
"1","(7000,4025)","0","mstr_symbols","I185";
;
CDS_LIB"mstr_symbols"
BOM_COST"PVPP_KLM_VR"
ROOM"PVPP_KLM_VR"
VOLTAGE"0"
SIZE"1B"
BODY_TYPE"PLUMBING"
HDL_POWER"GND";
"A\NAC"26;
%"SC22U16V5MX-4-GP"
"1","(7800,4275)","0","w_hdl","I186";
;
CDS_SEC"1"
CDS_LOCATION"C22W12"
VALUE"SC22U16V5MX-4-GP"
RATED"16V"
PACK_SIZE"0805"
TYPE"X6S"
TOLERANCE"20%"
ATTRIBUTE"22UF"
LOCATION"C22W12"
CDS_LMAN_SYM_OUTLINE"-50,25,50,-25"
CDS_LIB"w_hdl"
PART_NUMBER"078.22611.0811"
SEC_TYPE"SMD-BCG5"
SEC"1"
PACK_TYPE"SMD-BCG5";
"2"
$PN"2"25;
"1"
$PN"1"42;
%"IND-1UH-361-GP"
"1","(10500,4050)","1","w_hdl","I188";
;
CDS_SEC"1"
CDS_LOCATION"L8F1"
PACK_SIZE"DCR=4.6MOHM"
RATED"ISAT=24A@25C"
VALUE"IND-1UH-361-GP"
LOCATION"L8F1"
ATTRIBUTE"1.0UH"
PACK_TYPE"DISCRET-GC1"
SEC"1"
SEC_TYPE"DISCRET-GC1"
PART_NUMBER"068.1R010.1781"
CDS_LIB"w_hdl"
CDS_LMAN_SYM_OUTLINE"-50,100,50,-100";
"2"
$PN"2"27;
"1"
$PN"1"41;
%"ST470U6D3VDM-7-GP"
"1","(11100,3825)","0","w_hdl","I189";
;
CDS_SEC"1"
CDS_LOCATION"C8F14"
VALUE"ST470U6D3VDM-7-GP"
LOCATION"C8F14"
ATTRIBUTE"470UF"
TOLERANCE"IRP=1.7A"
RATED"6.3V"
TYPE"TMAX=105C"
PACK_SIZE"ESR=35MOHM"
CDS_LMAN_SYM_OUTLINE"-50,25,50,-25"
CDS_LIB"w_hdl"
PART_NUMBER"077.C4771.0061"
SEC_TYPE"SMD-TCG4"
SEC"1"
PACK_TYPE"SMD-TCG4";
"2"
$PN"2"11;
"1"
$PN"1"27;
%"ST470U6D3VDM-7-GP"
"1","(11500,3825)","0","w_hdl","I190";
;
CDS_SEC"1"
CDS_LOCATION"C8F8"
TYPE"TMAX=105C"
VALUE"ST470U6D3VDM-7-GP"
PACK_SIZE"ESR=35MOHM"
RATED"6.3V"
TOLERANCE"IRP=1.7A"
ATTRIBUTE"470UF"
LOCATION"C8F8"
PACK_TYPE"SMD-TCG4"
SEC"1"
SEC_TYPE"SMD-TCG4"
PART_NUMBER"077.C4771.0061"
CDS_LIB"w_hdl"
CDS_LMAN_SYM_OUTLINE"-50,25,50,-25";
"2"
$PN"2"12;
"1"
$PN"1"27;
%"SC4D7U16V3KX-GP"
"1","(5500,3275)","0","w_hdl","I191";
;
CDS_SEC"1"
CDS_LOCATION"C2R11"
LOCATION"C2R11"
VALUE"SC4D7U16V3KX-GP"
ATTRIBUTE"4.7UF"
TOLERANCE"10%"
RATED"16V"
PACK_SIZE"0603"
CDS_LMAN_SYM_OUTLINE"-50,25,50,-25"
CDS_LIB"w_hdl"
PART_NUMBER"078.47521.08BD"
SEC_TYPE"SMD-BCG5"
SEC"1"
PACK_TYPE"SMD-BCG5";
"2"
$PN"2"18;
"1"
$PN"1"2;
%"BLM31SN500SN1L-GP"
"1","(6100,4500)","1","w_hdl","I193";
;
CDS_SEC"1"
CDS_LOCATION"FB9E1"
VALUE"BLM31SN500SN1L-GP"
PACK_SIZE"DCR=1.6MOHM"
RATED"1MA"
LOCATION"FB9E1"
ATTRIBUTE"50OHM@100MHZ"
PACK_TYPE"DISCRET-GB1"
SEC"1"
SEC_TYPE"DISCRET-GB1"
PART_NUMBER"068.00007.0011"
CDS_LIB"w_hdl"
CDS_LMAN_SYM_OUTLINE"-50,100,50,-100";
"2"
$PN"2"42;
"1"
$PN"1"6;
%"RES"
"2","(6450,1850)","0","mstr_discrete","I195";
;
CDS_SEC"1"
CDS_LOCATION"R8F9"
VALUE"49.9K"
TOLERANCE"1%"
WATTAGE"1/16W"
MATERIAL"CHIP"
PACK_TYPE"0402"
PART_NUMBER"G21796-048"
LOCATION"R8F9"
CDS_LIB"mstr_discrete"
ROOM"V_SUPER"
SEC_TYPE"0402"
SEC"1";
"A"
$PN"1"40;
"B"
$PN"2"16;
%"P3V3_STBY"
"1","(12575,4225)","0","mstr_symbols","I85";
;
CDS_LIB"mstr_symbols"
SIZE"1B"
VOLTAGE"+3.3V"
BODY_TYPE"PLUMBING"
HDL_POWER"P3V3_STBY";
"G\NAC"27;
END.
